FILE_TYPE = MACRO_DRAWING;
SET COLOR_WIRE YELLOW;
SET COLOR_PROP MONO;
SET COLOR_DOT WHITE;
SET COLOR_ARC YELLOW;
SET COLOR_BODY GREEN;
SET COLOR_NOTE MONO;
SET PROP_DISPLAY VALUE;
SET PAGE_NUMBER P237;
FORCEADD OFFPAGE..2
(2975 3650);
FORCEPROP 2 LAST $XR0 235 
J 0
(3164 3650);
DISPLAY 0.638298 (3164 3650);
PAINT MONO (3164 3650);
FORCEPROP 2 LAST ROOM P1V8_PCH_STBY_VR
J 0
(2350 3725);
DISPLAY 1.212766 (2350 3725);
PAINT ORANGE (2350 3725);
DISPLAY INVISIBLE (2350 3725);
FORCEPROP 1 LAST COMMENT_BODY TRUE
J 0
(2930 3555);
PAINT PEACH (2930 3555);
DISPLAY INVISIBLE (2930 3555);
FORCEPROP 2 LAST CDS_LIB mstr_standard
J 0
(2975 3650);
DISPLAY 1.617021 (2975 3650);
PAINT MONO (2975 3650);
DISPLAY INVISIBLE (2975 3650);
FORCEPROP 2 LAST PATH I1
J 0
(3134 3724);
DISPLAY 1.021277 (3134 3724);
PAINT ORANGE (3134 3724);
DISPLAY INVISIBLE (3134 3724);
FORCEPROP 1 LAST OFFPAGE TRUE
J 0
(3300 3525);
PAINT GREEN (3300 3525);
DISPLAY INVISIBLE (3300 3525);
FORCEPROP 2 LAST BOM_COST P1V8_PCH_STBY_VR
J 0
(3285 3690);
DISPLAY 1.617021 (3285 3690);
PAINT MONO (3285 3690);
DISPLAY INVISIBLE (3285 3690);
FORCEADD CAP..1
(3375 2150);
FORCEPROP 1 LAST PACK_TYPE 0805
J 0
(3425 1950);
DISPLAY 0.617021 (3425 1950);
PAINT SKYBLUE (3425 1950);
FORCEPROP 1 LAST PART_NUMBER C95333-008
J 0
(3425 2000);
DISPLAY 0.617021 (3425 2000);
PAINT BLUE (3425 2000);
FORCEPROP 1 LASTPIN (3375 2050) $PN 2
J 0
(3385 2030);
DISPLAY 0.617021 (3385 2030);
PAINT WHITE (3385 2030);
FORCEPROP 1 LASTPIN (3375 2250) $PN 1
J 0
(3385 2230);
DISPLAY 0.617021 (3385 2230);
PAINT WHITE (3385 2230);
FORCEPROP 1 LAST LOCATION C2L45
J 0
(3425 2250);
DISPLAY 0.617021 (3425 2250);
PAINT AQUA (3425 2250);
FORCEPROP 1 LAST VALUE 22UF
J 0
(3425 2200);
DISPLAY 0.617021 (3425 2200);
PAINT SKYBLUE (3425 2200);
FORCEPROP 1 LAST MATERIAL X6S
J 0
(3425 2050);
DISPLAY 0.617021 (3425 2050);
PAINT SKYBLUE (3425 2050);
FORCEPROP 1 LAST VOLTAGE 6.3V
J 0
(3425 2150);
DISPLAY 0.617021 (3425 2150);
PAINT SKYBLUE (3425 2150);
FORCEPROP 1 LAST TOLERANCE 20%
J 0
(3425 2100);
DISPLAY 0.617021 (3425 2100);
PAINT SKYBLUE (3425 2100);
FORCEPROP 2 LAST CDS_LIB mstr_discrete
J 0
(3375 2150);
DISPLAY 1.617021 (3375 2150);
PAINT MONO (3375 2150);
DISPLAY INVISIBLE (3375 2150);
FORCEPROP 2 LAST CDS_LOCATION C2L45
J 0
(3425 2250);
DISPLAY 0.617021 (3425 2250);
PAINT AQUA (3425 2250);
DISPLAY INVISIBLE (3425 2250);
FORCEPROP 1 LAST PATH I12
J 0
(3425 2300);
DISPLAY 0.978723 (3425 2300);
PAINT WHITE (3425 2300);
DISPLAY INVISIBLE (3425 2300);
FORCEPROP 2 LAST BOM_COST P1V8_PCH_STBY_VR
J 0
(3425 2300);
DISPLAY 1.659574 (3425 2300);
PAINT MONO (3425 2300);
DISPLAY INVISIBLE (3425 2300);
FORCEPROP 2 LAST ROOM P1V8_PCH_STBY_VR
J 0
(3425 2300);
DISPLAY 1.659574 (3425 2300);
PAINT MONO (3425 2300);
DISPLAY INVISIBLE (3425 2300);
FORCEPROP 2 LAST $SEC 1
J 0
(3425 2350);
DISPLAY 1.510638 (3425 2350);
PAINT MONO (3425 2350);
DISPLAY INVISIBLE (3425 2350);
FORCEPROP 2 LAST CDS_SEC 1
J 0
(3425 2350);
DISPLAY 2.276596 (3425 2350);
PAINT ORANGE (3425 2350);
DISPLAY INVISIBLE (3425 2350);
FORCEADD CAP..1
(3100 2200);
FORCEPROP 1 LAST PACK_TYPE 0805
J 0
(3150 2000);
DISPLAY 0.617021 (3150 2000);
PAINT SKYBLUE (3150 2000);
FORCEPROP 1 LAST VALUE 22UF
J 0
(3150 2250);
DISPLAY 0.617021 (3150 2250);
PAINT SKYBLUE (3150 2250);
FORCEPROP 1 LASTPIN (3100 2100) $PN 2
J 0
(3110 2080);
DISPLAY 0.617021 (3110 2080);
PAINT WHITE (3110 2080);
FORCEPROP 1 LAST TOLERANCE 20%
J 0
(3150 2150);
DISPLAY 0.617021 (3150 2150);
PAINT SKYBLUE (3150 2150);
FORCEPROP 1 LAST VOLTAGE 6.3V
J 0
(3150 2200);
DISPLAY 0.617021 (3150 2200);
PAINT SKYBLUE (3150 2200);
FORCEPROP 1 LAST MATERIAL X6S
J 0
(3150 2100);
DISPLAY 0.617021 (3150 2100);
PAINT SKYBLUE (3150 2100);
FORCEPROP 1 LAST LOCATION C8A14
J 0
(3150 2300);
DISPLAY 0.617021 (3150 2300);
PAINT AQUA (3150 2300);
FORCEPROP 1 LASTPIN (3100 2300) $PN 1
J 0
(3110 2280);
DISPLAY 0.617021 (3110 2280);
PAINT WHITE (3110 2280);
FORCEPROP 1 LAST PART_NUMBER C95333-008
J 0
(3150 2050);
DISPLAY 0.617021 (3150 2050);
PAINT BLUE (3150 2050);
FORCEPROP 2 LAST CDS_LIB mstr_discrete
J 0
(3100 2200);
DISPLAY 1.617021 (3100 2200);
PAINT MONO (3100 2200);
DISPLAY INVISIBLE (3100 2200);
FORCEPROP 2 LAST CDS_LOCATION C8A14
J 0
(3150 2300);
DISPLAY 0.617021 (3150 2300);
PAINT AQUA (3150 2300);
DISPLAY INVISIBLE (3150 2300);
FORCEPROP 2 LAST SEC_TYPE 0805
J 0
(3150 2400);
DISPLAY 1.021277 (3150 2400);
PAINT ORANGE (3150 2400);
DISPLAY INVISIBLE (3150 2400);
FORCEPROP 2 LAST BOM_COST P1V8_PCH_STBY_VR
J 0
(3150 2350);
DISPLAY 1.659574 (3150 2350);
PAINT MONO (3150 2350);
DISPLAY INVISIBLE (3150 2350);
FORCEPROP 2 LAST ROOM P1V8_PCH_STBY_VR
J 0
(3150 2350);
DISPLAY 1.659574 (3150 2350);
PAINT MONO (3150 2350);
DISPLAY INVISIBLE (3150 2350);
FORCEPROP 2 LAST SEC 1
J 0
(3150 2400);
DISPLAY 1.510638 (3150 2400);
PAINT MONO (3150 2400);
DISPLAY INVISIBLE (3150 2400);
FORCEPROP 1 LAST PATH I13
J 0
(3150 2350);
DISPLAY 0.978723 (3150 2350);
PAINT WHITE (3150 2350);
DISPLAY INVISIBLE (3150 2350);
FORCEADD GND..1
(3500 1400);
FORCEPROP 3 LASTPIN (3500 1450) SIG_NAME GND\g
J 0
(3510 1460);
DISPLAY 0.659574 (3510 1460);
PAINT MONO (3510 1460);
DISPLAY INVISIBLE (3510 1460);
FORCEPROP 2 LAST ROOM P1V8_PCH_STBY_VR
J 0
(2850 1475);
DISPLAY 1.659574 (2850 1475);
PAINT ORANGE (2850 1475);
DISPLAY INVISIBLE (2850 1475);
FORCEPROP 1 LAST VOLTAGE 0.0V
J 0
(3455 1357);
DISPLAY 0.340426 (3455 1357);
PAINT SKYBLUE (3455 1357);
DISPLAY INVISIBLE (3455 1357);
FORCEPROP 2 LAST CDS_LIB mstr_symbols
J 0
(3500 1400);
DISPLAY 1.659574 (3500 1400);
PAINT MONO (3500 1400);
DISPLAY INVISIBLE (3500 1400);
FORCEPROP 1 LAST SIZE 1B
J 0
(3575 1350);
DISPLAY 1.489362 (3575 1350);
PAINT GREEN (3575 1350);
DISPLAY INVISIBLE (3575 1350);
FORCEPROP 1 LAST BODY_TYPE PLUMBING
J 0
(3455 1357);
DISPLAY 0.340426 (3455 1357);
PAINT GREEN (3455 1357);
DISPLAY INVISIBLE (3455 1357);
FORCEPROP 1 LAST PATH I14
J 0
(3575 1400);
DISPLAY 0.872340 (3575 1400);
PAINT AQUA (3575 1400);
DISPLAY INVISIBLE (3575 1400);
FORCEPROP 2 LAST BOM_COST P1V8_PCH_STBY_VR
J 0
(3100 1475);
DISPLAY 1.659574 (3100 1475);
PAINT MONO (3100 1475);
DISPLAY INVISIBLE (3100 1475);
FORCEPROP 1 LAST HDL_POWER GND
J 0
(3500 1550);
DISPLAY 1.489362 (3500 1550);
PAINT GREEN (3500 1550);
DISPLAY INVISIBLE (3500 1550);
FORCEADD RES..2
(2800 2125);
FORCEPROP 1 LAST PACK_TYPE 0603
J 0
(2840 1950);
DISPLAY 0.617021 (2840 1950);
PAINT SKYBLUE (2840 1950);
FORCEPROP 1 LAST PART_NUMBER G22026-030
J 0
(2840 2000);
DISPLAY 0.617021 (2840 2000);
PAINT BLUE (2840 2000);
FORCEPROP 1 LASTPIN (2800 2025) $PN 2
J 0
(2805 2035);
DISPLAY 0.617021 (2805 2035);
PAINT WHITE (2805 2035);
FORCEPROP 1 LASTPIN (2800 2225) $PN 1
J 0
(2805 2187);
DISPLAY 0.617021 (2805 2187);
PAINT WHITE (2805 2187);
FORCEPROP 1 LAST WATTAGE 1/10W
J 0
(2840 2100);
DISPLAY 0.617021 (2840 2100);
PAINT SKYBLUE (2840 2100);
FORCEPROP 1 LAST MATERIAL CHIP
J 0
(2840 2050);
DISPLAY 0.617021 (2840 2050);
PAINT SKYBLUE (2840 2050);
FORCEPROP 1 LAST TOLERANCE 1%
J 0
(2845 2150);
DISPLAY 0.617021 (2845 2150);
PAINT SKYBLUE (2845 2150);
FORCEPROP 1 LAST VALUE 475.0
J 0
(2845 2200);
DISPLAY 0.617021 (2845 2200);
PAINT SKYBLUE (2845 2200);
FORCEPROP 1 LAST LOCATION R8A12
J 0
(2845 2250);
DISPLAY 0.617021 (2845 2250);
PAINT AQUA (2845 2250);
FORCEPROP 2 LAST CDS_LIB mstr_discrete
J 0
(2800 2125);
DISPLAY 1.617021 (2800 2125);
PAINT RED (2800 2125);
DISPLAY INVISIBLE (2800 2125);
FORCEPROP 2 LAST ROOM P1V8_PCH_STBY_VR
J 0
(2845 2280);
DISPLAY 1.617021 (2845 2280);
PAINT MONO (2845 2280);
DISPLAY INVISIBLE (2845 2280);
FORCEPROP 1 LAST PATH I15
J 0
(2850 2300);
DISPLAY 0.978723 (2850 2300);
PAINT WHITE (2850 2300);
DISPLAY INVISIBLE (2850 2300);
FORCEPROP 2 LAST CDS_LOCATION R8A12
J 0
(2845 2250);
DISPLAY 0.617021 (2845 2250);
PAINT AQUA (2845 2250);
DISPLAY INVISIBLE (2845 2250);
FORCEPROP 2 LAST SEC 1
J 0
(2850 2350);
DISPLAY 0.680851 (2850 2350);
PAINT MONO (2850 2350);
DISPLAY INVISIBLE (2850 2350);
FORCEPROP 2 LAST BOM_COST P1V8_PCH_STBY_VR
J 0
(2845 2305);
DISPLAY 1.617021 (2845 2305);
PAINT MONO (2845 2305);
DISPLAY INVISIBLE (2845 2305);
FORCEPROP 2 LAST SEC_TYPE 0603
J 0
(2850 2350);
DISPLAY 1.021277 (2850 2350);
PAINT ORANGE (2850 2350);
DISPLAY INVISIBLE (2850 2350);
FORCEADD CAP..1
(-1975 3150);
FORCEPROP 1 LAST PART_NUMBER E15431-002
R 1
J 0
(-2025 2950);
DISPLAY 0.617021 (-2025 2950);
PAINT BLUE (-2025 2950);
FORCEPROP 1 LASTPIN (-1975 3050) $PN 2
J 0
(-1965 3030);
DISPLAY 0.617021 (-1965 3030);
PAINT WHITE (-1965 3030);
FORCEPROP 1 LAST PACK_TYPE 0603
J 0
(-1925 3000);
DISPLAY 0.617021 (-1925 3000);
PAINT SKYBLUE (-1925 3000);
FORCEPROP 1 LAST MATERIAL X6S
J 0
(-1925 3050);
DISPLAY 0.617021 (-1925 3050);
PAINT SKYBLUE (-1925 3050);
FORCEPROP 1 LASTPIN (-1975 3250) $PN 1
J 0
(-1965 3230);
DISPLAY 0.617021 (-1965 3230);
PAINT WHITE (-1965 3230);
FORCEPROP 1 LAST LOCATION C8A6
J 0
(-1925 3250);
DISPLAY 0.617021 (-1925 3250);
PAINT AQUA (-1925 3250);
FORCEPROP 1 LAST VALUE 10UF
J 0
(-1925 3200);
DISPLAY 0.617021 (-1925 3200);
PAINT SKYBLUE (-1925 3200);
FORCEPROP 1 LAST TOLERANCE 20%
J 0
(-1925 3100);
DISPLAY 0.617021 (-1925 3100);
PAINT SKYBLUE (-1925 3100);
FORCEPROP 1 LAST VOLTAGE 6.3V
J 0
(-1925 3150);
DISPLAY 0.617021 (-1925 3150);
PAINT SKYBLUE (-1925 3150);
FORCEPROP 2 LAST CDS_LIB mstr_discrete
J 0
(-1975 3150);
DISPLAY 1.617021 (-1975 3150);
PAINT MONO (-1975 3150);
DISPLAY INVISIBLE (-1975 3150);
FORCEPROP 2 LAST CDS_LOCATION C8A6
J 0
(-1925 3250);
DISPLAY 0.617021 (-1925 3250);
PAINT AQUA (-1925 3250);
DISPLAY INVISIBLE (-1925 3250);
FORCEPROP 2 LAST ROOM P1V8_PCH_STBY_VR
J 0
(-1915 3285);
DISPLAY 1.617021 (-1915 3285);
PAINT MONO (-1915 3285);
DISPLAY INVISIBLE (-1915 3285);
FORCEPROP 2 LAST BOM_COST P1V8_PCH_STBY_VR
J 0
(-1915 3285);
DISPLAY 1.617021 (-1915 3285);
PAINT MONO (-1915 3285);
DISPLAY INVISIBLE (-1915 3285);
FORCEPROP 1 LAST PATH I29
J 0
(-1925 3300);
DISPLAY 0.978723 (-1925 3300);
PAINT WHITE (-1925 3300);
DISPLAY INVISIBLE (-1925 3300);
FORCEPROP 2 LAST SEC 1
J 0
(-1925 3350);
DISPLAY 0.680851 (-1925 3350);
PAINT MONO (-1925 3350);
DISPLAY INVISIBLE (-1925 3350);
FORCEPROP 2 LAST SEC_TYPE 0603
J 0
(-1925 3350);
DISPLAY 1.021277 (-1925 3350);
PAINT ORANGE (-1925 3350);
DISPLAY INVISIBLE (-1925 3350);
FORCEADD RES..2
(1350 3875);
FORCEPROP 1 LASTPIN (1350 3775) $PN 2
J 0
(1355 3785);
DISPLAY 0.617021 (1355 3785);
PAINT WHITE (1355 3785);
FORCEPROP 1 LAST PACK_TYPE 0402
J 0
(1390 3700);
DISPLAY 0.617021 (1390 3700);
PAINT SKYBLUE (1390 3700);
FORCEPROP 1 LAST MATERIAL CHIP
J 0
(1390 3800);
DISPLAY 0.617021 (1390 3800);
PAINT SKYBLUE (1390 3800);
FORCEPROP 1 LASTPIN (1350 3975) $PN 1
J 0
(1355 3937);
DISPLAY 0.617021 (1355 3937);
PAINT WHITE (1355 3937);
FORCEPROP 1 LAST TOLERANCE 1%
J 0
(1395 3900);
DISPLAY 0.617021 (1395 3900);
PAINT SKYBLUE (1395 3900);
FORCEPROP 1 LAST WATTAGE 1/16W
J 0
(1390 3850);
DISPLAY 0.617021 (1390 3850);
PAINT SKYBLUE (1390 3850);
FORCEPROP 1 LAST VALUE 5.11K
J 0
(1395 3950);
DISPLAY 0.617021 (1395 3950);
PAINT SKYBLUE (1395 3950);
FORCEPROP 1 LAST PART_NUMBER G21796-140
J 0
(1390 3750);
DISPLAY 0.617021 (1390 3750);
PAINT BLUE (1390 3750);
FORCEPROP 1 LAST LOCATION R8A10
J 0
(1395 4000);
DISPLAY 0.617021 (1395 4000);
PAINT AQUA (1395 4000);
FORCEPROP 2 LAST CDS_LIB mstr_discrete
J 0
(1350 3875);
DISPLAY 1.617021 (1350 3875);
PAINT MONO (1350 3875);
DISPLAY INVISIBLE (1350 3875);
FORCEPROP 1 LAST PATH I3
J 0
(1400 4050);
DISPLAY 0.978723 (1400 4050);
PAINT WHITE (1400 4050);
DISPLAY INVISIBLE (1400 4050);
FORCEPROP 2 LAST CDS_LOCATION R8A10
J 0
(1395 4000);
DISPLAY 0.617021 (1395 4000);
PAINT AQUA (1395 4000);
DISPLAY INVISIBLE (1395 4000);
FORCEPROP 2 LAST ROOM P1V8_PCH_STBY_VR
J 0
(1410 4040);
DISPLAY 1.617021 (1410 4040);
PAINT MONO (1410 4040);
DISPLAY INVISIBLE (1410 4040);
FORCEPROP 2 LAST BOM_COST P1V8_PCH_STBY_VR
J 0
(1410 4040);
DISPLAY 1.617021 (1410 4040);
PAINT MONO (1410 4040);
DISPLAY INVISIBLE (1410 4040);
FORCEPROP 2 LAST $SEC 1
J 0
(1410 4115);
DISPLAY 1.617021 (1410 4115);
PAINT MONO (1410 4115);
DISPLAY INVISIBLE (1410 4115);
FORCEPROP 2 LAST CDS_SEC 1
J 0
(1410 4115);
DISPLAY 1.617021 (1410 4115);
PAINT MONO (1410 4115);
DISPLAY INVISIBLE (1410 4115);
FORCEADD GND..1
(-1975 2800);
FORCEPROP 3 LASTPIN (-1975 2850) SIG_NAME GND\g
J 0
(-1965 2860);
DISPLAY 0.659574 (-1965 2860);
PAINT MONO (-1965 2860);
DISPLAY INVISIBLE (-1965 2860);
FORCEPROP 2 LAST ROOM P1V8_PCH_STBY_VR
J 0
(-2625 2875);
DISPLAY 1.212766 (-2625 2875);
PAINT ORANGE (-2625 2875);
DISPLAY INVISIBLE (-2625 2875);
FORCEPROP 2 LAST BOM_COST P1V8_PCH_STBY_VR
J 0
(-2290 2895);
DISPLAY 1.617021 (-2290 2895);
PAINT MONO (-2290 2895);
DISPLAY INVISIBLE (-2290 2895);
FORCEPROP 1 LAST VOLTAGE 0.0V
J 0
(-2020 2757);
DISPLAY 0.340426 (-2020 2757);
PAINT SKYBLUE (-2020 2757);
DISPLAY INVISIBLE (-2020 2757);
FORCEPROP 1 LAST SIZE 1B
J 0
(-1900 2750);
DISPLAY 1.042553 (-1900 2750);
PAINT GREEN (-1900 2750);
DISPLAY INVISIBLE (-1900 2750);
FORCEPROP 1 LAST BODY_TYPE PLUMBING
J 0
(-2020 2757);
DISPLAY 0.340426 (-2020 2757);
PAINT GREEN (-2020 2757);
DISPLAY INVISIBLE (-2020 2757);
FORCEPROP 2 LAST CDS_LIB mstr_symbols
J 0
(-1975 2800);
DISPLAY 1.617021 (-1975 2800);
PAINT MONO (-1975 2800);
DISPLAY INVISIBLE (-1975 2800);
FORCEPROP 1 LAST PATH I30
J 0
(-1900 2800);
DISPLAY 0.872340 (-1900 2800);
PAINT AQUA (-1900 2800);
DISPLAY INVISIBLE (-1900 2800);
FORCEPROP 1 LAST HDL_POWER GND
J 0
(-1975 2950);
DISPLAY 1.042553 (-1975 2950);
PAINT GREEN (-1975 2950);
DISPLAY INVISIBLE (-1975 2950);
FORCEADD CAP..1
(-1550 3175);
FORCEPROP 1 LAST PACK_TYPE 0603LF
J 0
(-1500 2975);
DISPLAY 0.617021 (-1500 2975);
PAINT SKYBLUE (-1500 2975);
FORCEPROP 1 LASTPIN (-1550 3075) $PN 2
J 0
(-1540 3055);
DISPLAY 0.617021 (-1540 3055);
PAINT WHITE (-1540 3055);
FORCEPROP 1 LASTPIN (-1550 3275) $PN 1
J 0
(-1540 3255);
DISPLAY 0.617021 (-1540 3255);
PAINT WHITE (-1540 3255);
FORCEPROP 1 LAST MATERIAL X7R
J 0
(-1500 3075);
DISPLAY 0.617021 (-1500 3075);
PAINT SKYBLUE (-1500 3075);
FORCEPROP 1 LAST VOLTAGE 25V
J 0
(-1500 3175);
DISPLAY 0.617021 (-1500 3175);
PAINT SKYBLUE (-1500 3175);
FORCEPROP 1 LAST TOLERANCE 10%
J 0
(-1500 3125);
DISPLAY 0.617021 (-1500 3125);
PAINT SKYBLUE (-1500 3125);
FORCEPROP 1 LAST VALUE 0.1UF
J 0
(-1500 3225);
DISPLAY 0.617021 (-1500 3225);
PAINT SKYBLUE (-1500 3225);
FORCEPROP 1 LAST LOCATION C8A4
J 0
(-1500 3275);
DISPLAY 0.617021 (-1500 3275);
PAINT AQUA (-1500 3275);
FORCEPROP 1 LAST PART_NUMBER 602433-020
J 0
(-1500 3025);
DISPLAY 0.617021 (-1500 3025);
PAINT BLUE (-1500 3025);
FORCEPROP 2 LAST CDS_LIB mstr_discrete
J 0
(-1550 3175);
DISPLAY 1.617021 (-1550 3175);
PAINT MONO (-1550 3175);
DISPLAY INVISIBLE (-1550 3175);
FORCEPROP 2 LAST ROOM P1V8_PCH_STBY_VR
J 0
(-1550 3300);
DISPLAY 1.212766 (-1550 3300);
PAINT ORANGE (-1550 3300);
DISPLAY INVISIBLE (-1550 3300);
FORCEPROP 1 LAST PATH I31
J 0
(-1500 3325);
DISPLAY 0.978723 (-1500 3325);
PAINT WHITE (-1500 3325);
DISPLAY INVISIBLE (-1500 3325);
FORCEPROP 2 LAST CDS_LOCATION C8A4
J 0
(-1500 3275);
DISPLAY 0.617021 (-1500 3275);
PAINT AQUA (-1500 3275);
DISPLAY INVISIBLE (-1500 3275);
FORCEPROP 2 LAST SEC 1
J 0
(-1500 3375);
DISPLAY 0.680851 (-1500 3375);
PAINT MONO (-1500 3375);
DISPLAY INVISIBLE (-1500 3375);
FORCEPROP 2 LAST SEC_TYPE 0603LF
J 0
(-1500 3375);
DISPLAY 1.021277 (-1500 3375);
PAINT ORANGE (-1500 3375);
DISPLAY INVISIBLE (-1500 3375);
FORCEPROP 2 LAST BOM_COST P1V8_PCH_STBY_VR
J 0
(-1485 3320);
DISPLAY 1.617021 (-1485 3320);
PAINT MONO (-1485 3320);
DISPLAY INVISIBLE (-1485 3320);
FORCEADD GND..1
(-1550 2775);
FORCEPROP 3 LASTPIN (-1550 2825) SIG_NAME GND\g
J 0
(-1540 2835);
DISPLAY 0.659574 (-1540 2835);
PAINT MONO (-1540 2835);
DISPLAY INVISIBLE (-1540 2835);
FORCEPROP 2 LAST ROOM P1V8_PCH_STBY_VR
J 0
(-2200 2850);
DISPLAY 1.212766 (-2200 2850);
PAINT ORANGE (-2200 2850);
DISPLAY INVISIBLE (-2200 2850);
FORCEPROP 2 LAST BOM_COST P1V8_PCH_STBY_VR
J 0
(-1860 2870);
DISPLAY 1.617021 (-1860 2870);
PAINT MONO (-1860 2870);
DISPLAY INVISIBLE (-1860 2870);
FORCEPROP 1 LAST VOLTAGE 0.0V
J 0
(-1595 2732);
DISPLAY 0.340426 (-1595 2732);
PAINT SKYBLUE (-1595 2732);
DISPLAY INVISIBLE (-1595 2732);
FORCEPROP 2 LAST CDS_LIB mstr_symbols
J 0
(-1550 2775);
DISPLAY 1.617021 (-1550 2775);
PAINT MONO (-1550 2775);
DISPLAY INVISIBLE (-1550 2775);
FORCEPROP 1 LAST BODY_TYPE PLUMBING
J 0
(-1595 2732);
DISPLAY 0.340426 (-1595 2732);
PAINT GREEN (-1595 2732);
DISPLAY INVISIBLE (-1595 2732);
FORCEPROP 1 LAST HDL_POWER GND
J 0
(-1550 2925);
DISPLAY 1.042553 (-1550 2925);
PAINT GREEN (-1550 2925);
DISPLAY INVISIBLE (-1550 2925);
FORCEPROP 1 LAST PATH I32
J 0
(-1475 2775);
DISPLAY 0.872340 (-1475 2775);
PAINT AQUA (-1475 2775);
DISPLAY INVISIBLE (-1475 2775);
FORCEPROP 1 LAST SIZE 1B
J 0
(-1475 2725);
DISPLAY 1.042553 (-1475 2725);
PAINT GREEN (-1475 2725);
DISPLAY INVISIBLE (-1475 2725);
FORCEADD P1V8_PCH_STBY..1
(3925 2850);
FORCEPROP 3 LASTPIN (3925 2800) SIG_NAME P1V8_PCH_STBY\g
J 0
(3935 2810);
DISPLAY 0.659574 (3935 2810);
PAINT MONO (3935 2810);
DISPLAY INVISIBLE (3935 2810);
FORCEPROP 1 LAST BODY_TYPE PLUMBING
J 0
(3880 2807);
DISPLAY 0.340426 (3880 2807);
PAINT GREEN (3880 2807);
DISPLAY INVISIBLE (3880 2807);
FORCEPROP 1 LAST VOLTAGE 1.8V
J 0
(3880 2807);
DISPLAY 0.340426 (3880 2807);
PAINT SKYBLUE (3880 2807);
DISPLAY INVISIBLE (3880 2807);
FORCEPROP 1 LAST HDL_POWER P1V8_PCH_STBY
J 1
(3925 2900);
DISPLAY 0.872340 (3925 2900);
PAINT GREEN (3925 2900);
DISPLAY INVISIBLE (3925 2900);
FORCEPROP 2 LAST ROOM P1V8_PCH_STBY_VR
J 0
(3950 2950);
DISPLAY 1.659574 (3950 2950);
PAINT ORANGE (3950 2950);
DISPLAY INVISIBLE (3950 2950);
FORCEPROP 1 LAST PATH I4
J 0
(3975 2875);
DISPLAY 0.872340 (3975 2875);
PAINT AQUA (3975 2875);
DISPLAY INVISIBLE (3975 2875);
FORCEPROP 2 LAST BOM_COST P1V8_PCH_STBY_VR
J 0
(3950 2950);
DISPLAY 1.659574 (3950 2950);
PAINT MONO (3950 2950);
DISPLAY INVISIBLE (3950 2950);
FORCEPROP 2 LAST CDS_LIB mstr_symbols
J 0
(3925 2850);
PAINT ORANGE (3925 2850);
DISPLAY INVISIBLE (3925 2850);
FORCEADD CAP..1
(1350 3475);
FORCEPROP 1 LASTPIN (1350 3575) $PN 1
J 0
(1360 3555);
DISPLAY 0.617021 (1360 3555);
PAINT WHITE (1360 3555);
FORCEPROP 1 LASTPIN (1350 3375) $PN 2
J 0
(1360 3355);
DISPLAY 0.617021 (1360 3355);
PAINT WHITE (1360 3355);
FORCEPROP 1 LAST MATERIAL X7R
J 0
(1400 3375);
DISPLAY 0.617021 (1400 3375);
PAINT SKYBLUE (1400 3375);
FORCEPROP 1 LAST VOLTAGE 50V
J 0
(1400 3475);
DISPLAY 0.617021 (1400 3475);
PAINT SKYBLUE (1400 3475);
FORCEPROP 1 LAST TOLERANCE 10%
J 0
(1400 3425);
DISPLAY 0.617021 (1400 3425);
PAINT SKYBLUE (1400 3425);
FORCEPROP 1 LAST PACK_TYPE 0402LF
J 0
(1400 3275);
DISPLAY 0.617021 (1400 3275);
PAINT SKYBLUE (1400 3275);
FORCEPROP 1 LAST VALUE 1000PF
J 0
(1400 3525);
DISPLAY 0.617021 (1400 3525);
PAINT SKYBLUE (1400 3525);
FORCEPROP 1 LAST PART_NUMBER A36096-046
J 0
(1400 3325);
DISPLAY 0.617021 (1400 3325);
PAINT BLUE (1400 3325);
FORCEPROP 1 LAST LOCATION C8A11
J 0
(1400 3575);
DISPLAY 0.617021 (1400 3575);
PAINT AQUA (1400 3575);
FORCEPROP 2 LAST CDS_LIB mstr_discrete
J 0
(1350 3475);
DISPLAY 1.617021 (1350 3475);
PAINT MONO (1350 3475);
DISPLAY INVISIBLE (1350 3475);
FORCEPROP 2 LAST CDS_LOCATION C8A11
J 0
(1400 3575);
DISPLAY 0.617021 (1400 3575);
PAINT AQUA (1400 3575);
DISPLAY INVISIBLE (1400 3575);
FORCEPROP 1 LAST PATH I5
J 0
(1400 3625);
DISPLAY 0.978723 (1400 3625);
PAINT WHITE (1400 3625);
DISPLAY INVISIBLE (1400 3625);
FORCEPROP 2 LAST CDS_SEC 1
J 0
(1410 3690);
DISPLAY 1.617021 (1410 3690);
PAINT MONO (1410 3690);
DISPLAY INVISIBLE (1410 3690);
FORCEPROP 2 LAST BOM_COST P1V8_PCH_STBY_VR
J 0
(1410 3615);
DISPLAY 1.617021 (1410 3615);
PAINT MONO (1410 3615);
DISPLAY INVISIBLE (1410 3615);
FORCEPROP 2 LAST ROOM P1V8_PCH_STBY_VR
J 0
(1410 3615);
DISPLAY 1.617021 (1410 3615);
PAINT MONO (1410 3615);
DISPLAY INVISIBLE (1410 3615);
FORCEPROP 2 LAST $SEC 1
J 0
(1410 3690);
DISPLAY 1.617021 (1410 3690);
PAINT MONO (1410 3690);
DISPLAY INVISIBLE (1410 3690);
FORCEADD CAP..1
R 2
(-1500 2200);
FORCEPROP 1 LAST PART_NUMBER A36096-046
J 2
(-1550 2050);
DISPLAY 0.617021 (-1550 2050);
PAINT BLUE (-1550 2050);
FORCEPROP 1 LAST VALUE 1000PF
J 2
(-1550 2225);
DISPLAY 0.617021 (-1550 2225);
PAINT SKYBLUE (-1550 2225);
FORCEPROP 1 LAST LOCATION C8A10
J 2
(-1550 2275);
DISPLAY 0.617021 (-1550 2275);
PAINT AQUA (-1550 2275);
FORCEPROP 1 LAST MATERIAL EMPTY
J 2
(-1550 2100);
DISPLAY 0.617021 (-1550 2100);
PAINT RED (-1550 2100);
FORCEPROP 1 LAST TOLERANCE 10%
J 2
(-1550 2150);
DISPLAY 0.617021 (-1550 2150);
PAINT SKYBLUE (-1550 2150);
FORCEPROP 1 LAST VOLTAGE 50V
J 2
(-1550 2200);
DISPLAY 0.617021 (-1550 2200);
PAINT SKYBLUE (-1550 2200);
FORCEPROP 1 LASTPIN (-1500 2300) $PN 1
J 2
(-1510 2280);
DISPLAY 0.617021 (-1510 2280);
PAINT WHITE (-1510 2280);
FORCEPROP 1 LASTPIN (-1500 2100) $PN 2
J 2
(-1510 2080);
DISPLAY 0.617021 (-1510 2080);
PAINT WHITE (-1510 2080);
FORCEPROP 1 LAST PACK_TYPE 0402LF
J 2
(-1550 2000);
DISPLAY 0.617021 (-1550 2000);
PAINT SKYBLUE (-1550 2000);
FORCEPROP 2 LAST CDS_LOCATION C8A10
J 2
(-1550 2275);
DISPLAY 0.617021 (-1550 2275);
PAINT AQUA (-1550 2275);
DISPLAY INVISIBLE (-1550 2275);
FORCEPROP 2 LAST ROOM P1V8_PCH_STBY_VR
J 2
(-1550 2325);
DISPLAY 1.659574 (-1550 2325);
PAINT ORANGE (-1550 2325);
DISPLAY INVISIBLE (-1550 2325);
FORCEPROP 1 LAST PATH I55
J 2
(-1550 2350);
DISPLAY 0.978723 (-1550 2350);
PAINT WHITE (-1550 2350);
DISPLAY INVISIBLE (-1550 2350);
FORCEPROP 2 LAST $SEC 1
J 0
(-1550 2405);
DISPLAY 1.510638 (-1550 2405);
PAINT MONO (-1550 2405);
DISPLAY INVISIBLE (-1550 2405);
FORCEPROP 2 LAST CDS_SEC 1
J 0
(-1550 2405);
DISPLAY 2.276596 (-1550 2405);
PAINT ORANGE (-1550 2405);
DISPLAY INVISIBLE (-1550 2405);
FORCEPROP 2 LAST BOM_COST P1V8_PCH_STBY_VR
J 0
(-1575 2325);
DISPLAY 1.659574 (-1575 2325);
PAINT MONO (-1575 2325);
DISPLAY INVISIBLE (-1575 2325);
FORCEPROP 2 LAST CDS_LIB mstr_discrete
J 0
(-1500 2200);
DISPLAY 1.617021 (-1500 2200);
PAINT MONO (-1500 2200);
DISPLAY INVISIBLE (-1500 2200);
FORCEADD OFFPAGE..1
(-2750 2525);
FORCEPROP 2 LAST $XR0 240 
J 0
(-3002 2525);
DISPLAY 0.638298 (-3002 2525);
PAINT MONO (-3002 2525);
FORCEPROP 2 LAST $XR1 101 
J 0
(-3122 2525);
DISPLAY 0.638298 (-3122 2525);
PAINT MONO (-3122 2525);
FORCEPROP 2 LAST $XR2 189 
J 0
(-3242 2525);
DISPLAY 0.638298 (-3242 2525);
PAINT MONO (-3242 2525);
FORCEPROP 2 LAST $XR3 191 
J 0
(-3362 2525);
DISPLAY 0.638298 (-3362 2525);
PAINT MONO (-3362 2525);
FORCEPROP 2 LAST $XR4 196 
J 0
(-3482 2525);
DISPLAY 0.638298 (-3482 2525);
PAINT MONO (-3482 2525);
FORCEPROP 2 LAST $XR5 239 
J 0
(-3602 2525);
DISPLAY 0.638298 (-3602 2525);
PAINT MONO (-3602 2525);
FORCEPROP 2 LASTPIN (-2700 2525) SIG_NAME PWRGD_P3V3_STBY
J 0
(-2710 2535);
DISPLAY 0.617021 (-2710 2535);
PAINT ORANGE (-2710 2535);
FORCEPROP 1 LAST COMMENT_BODY TRUE
J 0
(-2625 2425);
DISPLAY 1.127660 (-2625 2425);
PAINT PEACH (-2625 2425);
DISPLAY INVISIBLE (-2625 2425);
FORCEPROP 2 LAST CDS_LIB mstr_standard
J 0
(-2750 2525);
DISPLAY 1.617021 (-2750 2525);
PAINT ORANGE (-2750 2525);
DISPLAY INVISIBLE (-2750 2525);
FORCEPROP 2 LAST PATH I58
J 0
(-2686 2599);
DISPLAY 1.021277 (-2686 2599);
PAINT ORANGE (-2686 2599);
DISPLAY INVISIBLE (-2686 2599);
FORCEPROP 2 LAST ROOM P1V8_PCH_STBY_VR
J 0
(-3000 2575);
DISPLAY 1.127660 (-3000 2575);
PAINT ORANGE (-3000 2575);
DISPLAY INVISIBLE (-3000 2575);
FORCEPROP 2 LAST BOM_COST P1V8_PCH_STBY_VR
J 0
(-3000 2575);
DISPLAY 1.617021 (-3000 2575);
PAINT MONO (-3000 2575);
DISPLAY INVISIBLE (-3000 2575);
FORCEPROP 1 LAST OFFPAGE TRUE
J 0
(-2425 2400);
PAINT GREEN (-2425 2400);
DISPLAY INVISIBLE (-2425 2400);
FORCEADD GND..1
(1350 3150);
FORCEPROP 3 LASTPIN (1350 3200) SIG_NAME GND\g
J 0
(1360 3210);
DISPLAY 0.659574 (1360 3210);
PAINT MONO (1360 3210);
DISPLAY INVISIBLE (1360 3210);
FORCEPROP 2 LAST ROOM P1V8_PCH_STBY_VR
J 0
(700 3225);
DISPLAY 1.212766 (700 3225);
PAINT ORANGE (700 3225);
DISPLAY INVISIBLE (700 3225);
FORCEPROP 2 LAST BOM_COST P1V8_PCH_STBY_VR
J 0
(1035 3240);
DISPLAY 1.617021 (1035 3240);
PAINT MONO (1035 3240);
DISPLAY INVISIBLE (1035 3240);
FORCEPROP 1 LAST PATH I6
J 0
(1425 3150);
DISPLAY 0.872340 (1425 3150);
PAINT AQUA (1425 3150);
DISPLAY INVISIBLE (1425 3150);
FORCEPROP 1 LAST BODY_TYPE PLUMBING
J 0
(1305 3107);
DISPLAY 0.340426 (1305 3107);
PAINT GREEN (1305 3107);
DISPLAY INVISIBLE (1305 3107);
FORCEPROP 2 LAST CDS_LIB mstr_symbols
J 0
(1350 3150);
DISPLAY 1.617021 (1350 3150);
PAINT MONO (1350 3150);
DISPLAY INVISIBLE (1350 3150);
FORCEPROP 1 LAST VOLTAGE 0.0V
J 0
(1305 3107);
DISPLAY 0.340426 (1305 3107);
PAINT SKYBLUE (1305 3107);
DISPLAY INVISIBLE (1305 3107);
FORCEPROP 1 LAST SIZE 1B
J 0
(1425 3100);
DISPLAY 1.042553 (1425 3100);
PAINT GREEN (1425 3100);
DISPLAY INVISIBLE (1425 3100);
FORCEPROP 1 LAST HDL_POWER GND
J 0
(1350 3300);
DISPLAY 1.042553 (1350 3300);
PAINT GREEN (1350 3300);
DISPLAY INVISIBLE (1350 3300);
FORCEADD P3V3_STBY..1
(1350 4125);
FORCEPROP 3 LASTPIN (1350 4075) SIG_NAME P3V3_STBY\g
J 0
(1360 4085);
DISPLAY 0.659574 (1360 4085);
PAINT MONO (1360 4085);
DISPLAY INVISIBLE (1360 4085);
FORCEPROP 1 LAST HDL_POWER P3V3_STBY
J 0
(1050 4000);
DISPLAY 0.872340 (1050 4000);
PAINT ORANGE (1050 4000);
DISPLAY INVISIBLE (1050 4000);
FORCEPROP 1 LAST BODY_TYPE PLUMBING
J 0
(1305 4082);
DISPLAY 0.340426 (1305 4082);
PAINT GREEN (1305 4082);
DISPLAY INVISIBLE (1305 4082);
FORCEPROP 1 LAST VOLTAGE 3.3V
J 0
(1305 4082);
DISPLAY 0.340426 (1305 4082);
PAINT SKYBLUE (1305 4082);
DISPLAY INVISIBLE (1305 4082);
FORCEPROP 1 LAST PATH I65
J 0
(1395 4127);
DISPLAY 0.340426 (1395 4127);
PAINT GREEN (1395 4127);
DISPLAY INVISIBLE (1395 4127);
FORCEPROP 2 LAST CDS_LIB mstr_symbols
J 0
(1350 4125);
PAINT ORANGE (1350 4125);
DISPLAY INVISIBLE (1350 4125);
FORCEPROP 1 LAST SIZE 1B
J 0
(1395 4147);
DISPLAY 0.340426 (1395 4147);
PAINT GREEN (1395 4147);
DISPLAY INVISIBLE (1395 4147);
FORCEADD GND..1
(525 2300);
FORCEPROP 3 LASTPIN (525 2350) SIG_NAME GND\g
J 0
(535 2360);
DISPLAY 0.659574 (535 2360);
PAINT MONO (535 2360);
DISPLAY INVISIBLE (535 2360);
FORCEPROP 2 LAST ROOM P1V8_PCH_STBY_VR
J 0
(-125 2375);
DISPLAY 1.212766 (-125 2375);
PAINT ORANGE (-125 2375);
DISPLAY INVISIBLE (-125 2375);
FORCEPROP 1 LAST BODY_TYPE PLUMBING
J 0
(480 2257);
DISPLAY 0.340426 (480 2257);
PAINT GREEN (480 2257);
DISPLAY INVISIBLE (480 2257);
FORCEPROP 2 LAST BOM_COST P1V8_PCH_STBY_VR
J 0
(210 2395);
DISPLAY 1.617021 (210 2395);
PAINT MONO (210 2395);
DISPLAY INVISIBLE (210 2395);
FORCEPROP 1 LAST VOLTAGE 0.0V
J 0
(480 2257);
DISPLAY 0.340426 (480 2257);
PAINT SKYBLUE (480 2257);
DISPLAY INVISIBLE (480 2257);
FORCEPROP 1 LAST HDL_POWER GND
J 0
(525 2450);
DISPLAY 1.042553 (525 2450);
PAINT GREEN (525 2450);
DISPLAY INVISIBLE (525 2450);
FORCEPROP 1 LAST PATH I71
J 0
(600 2300);
DISPLAY 0.872340 (600 2300);
PAINT AQUA (600 2300);
DISPLAY INVISIBLE (600 2300);
FORCEPROP 1 LAST SIZE 1B
J 0
(600 2250);
DISPLAY 1.042553 (600 2250);
PAINT GREEN (600 2250);
DISPLAY INVISIBLE (600 2250);
FORCEPROP 2 LAST CDS_LIB mstr_symbols
J 0
(525 2300);
PAINT ORANGE (525 2300);
DISPLAY INVISIBLE (525 2300);
FORCEADD CAP..1
(3650 2200);
FORCEPROP 1 LAST PACK_TYPE 0805
J 0
(3700 2000);
DISPLAY 0.617021 (3700 2000);
PAINT SKYBLUE (3700 2000);
FORCEPROP 1 LAST VALUE 47UF
J 0
(3700 2250);
DISPLAY 0.617021 (3700 2250);
PAINT SKYBLUE (3700 2250);
FORCEPROP 1 LAST MATERIAL X6S
J 0
(3700 2100);
DISPLAY 0.617021 (3700 2100);
PAINT SKYBLUE (3700 2100);
FORCEPROP 1 LAST VOLTAGE 4V
J 0
(3700 2200);
DISPLAY 0.617021 (3700 2200);
PAINT SKYBLUE (3700 2200);
FORCEPROP 1 LAST TOLERANCE 20%
J 0
(3700 2150);
DISPLAY 0.617021 (3700 2150);
PAINT SKYBLUE (3700 2150);
FORCEPROP 1 LASTPIN (3650 2100) $PN 2
J 0
(3660 2080);
DISPLAY 0.617021 (3660 2080);
PAINT ORANGE (3660 2080);
FORCEPROP 1 LASTPIN (3650 2300) $PN 1
J 0
(3660 2280);
DISPLAY 0.617021 (3660 2280);
PAINT ORANGE (3660 2280);
FORCEPROP 1 LAST LOCATION C8A12
J 0
(3700 2300);
DISPLAY 0.617021 (3700 2300);
PAINT AQUA (3700 2300);
FORCEPROP 1 LAST PART_NUMBER C95333-006
J 0
(3700 2050);
DISPLAY 0.617021 (3700 2050);
PAINT BLUE (3700 2050);
FORCEPROP 2 LAST CDS_LIB mstr_discrete
J 0
(3650 2200);
PAINT ORANGE (3650 2200);
DISPLAY INVISIBLE (3650 2200);
FORCEPROP 2 LAST CDS_LOCATION C8A12
J 0
(3700 2300);
DISPLAY 0.617021 (3700 2300);
PAINT AQUA (3700 2300);
DISPLAY INVISIBLE (3700 2300);
FORCEPROP 2 LAST ROOM P1V8_PCH_STBY_VR
J 0
(3700 2350);
PAINT MONO (3700 2350);
DISPLAY INVISIBLE (3700 2350);
FORCEPROP 1 LAST PATH I77
J 0
(3700 2350);
DISPLAY 0.978723 (3700 2350);
PAINT WHITE (3700 2350);
DISPLAY INVISIBLE (3700 2350);
FORCEPROP 2 LAST SEC 1
J 0
(3700 2400);
DISPLAY 0.680851 (3700 2400);
PAINT MONO (3700 2400);
DISPLAY INVISIBLE (3700 2400);
FORCEPROP 2 LAST SEC_TYPE 0805
J 0
(3700 2400);
DISPLAY 1.021277 (3700 2400);
PAINT ORANGE (3700 2400);
DISPLAY INVISIBLE (3700 2400);
FORCEADD CAP..1
(3900 1850);
FORCEPROP 1 LASTPIN (3900 1750) $PN 2
J 0
(3910 1730);
DISPLAY 0.617021 (3910 1730);
PAINT ORANGE (3910 1730);
FORCEPROP 1 LAST MATERIAL X6S
J 0
(3950 1750);
DISPLAY 0.617021 (3950 1750);
PAINT SKYBLUE (3950 1750);
FORCEPROP 1 LAST PACK_TYPE 0805
J 0
(3950 1650);
DISPLAY 0.617021 (3950 1650);
PAINT SKYBLUE (3950 1650);
FORCEPROP 1 LAST LOCATION C2L32
J 0
(3950 1950);
DISPLAY 0.617021 (3950 1950);
PAINT AQUA (3950 1950);
FORCEPROP 1 LAST VALUE 47UF
J 0
(3950 1900);
DISPLAY 0.617021 (3950 1900);
PAINT SKYBLUE (3950 1900);
FORCEPROP 1 LAST TOLERANCE 20%
J 0
(3950 1800);
DISPLAY 0.617021 (3950 1800);
PAINT SKYBLUE (3950 1800);
FORCEPROP 1 LAST VOLTAGE 4V
J 0
(3950 1850);
DISPLAY 0.617021 (3950 1850);
PAINT SKYBLUE (3950 1850);
FORCEPROP 1 LASTPIN (3900 1950) $PN 1
J 0
(3910 1930);
DISPLAY 0.617021 (3910 1930);
PAINT ORANGE (3910 1930);
FORCEPROP 1 LAST PART_NUMBER C95333-006
J 0
(3950 1700);
DISPLAY 0.617021 (3950 1700);
PAINT BLUE (3950 1700);
FORCEPROP 2 LAST CDS_LIB mstr_discrete
J 0
(3900 1850);
PAINT ORANGE (3900 1850);
DISPLAY INVISIBLE (3900 1850);
FORCEPROP 2 LAST CDS_LOCATION C2L32
J 0
(3950 1950);
DISPLAY 0.617021 (3950 1950);
PAINT AQUA (3950 1950);
DISPLAY INVISIBLE (3950 1950);
FORCEPROP 1 LAST PATH I79
J 0
(3950 2000);
DISPLAY 0.978723 (3950 2000);
PAINT WHITE (3950 2000);
DISPLAY INVISIBLE (3950 2000);
FORCEPROP 2 LAST ROOM P1V8_PCH_STBY_VR
J 0
(3950 2000);
PAINT MONO (3950 2000);
DISPLAY INVISIBLE (3950 2000);
FORCEPROP 2 LAST SEC 1
J 0
(3950 2050);
DISPLAY 0.680851 (3950 2050);
PAINT MONO (3950 2050);
DISPLAY INVISIBLE (3950 2050);
FORCEPROP 2 LAST SEC_TYPE 0805
J 0
(3950 2050);
DISPLAY 1.021277 (3950 2050);
PAINT ORANGE (3950 2050);
DISPLAY INVISIBLE (3950 2050);
FORCEADD RES..2
(2325 1700);
FORCEPROP 1 LAST PACK_TYPE 0402
J 0
(2365 1525);
DISPLAY 0.617021 (2365 1525);
PAINT SKYBLUE (2365 1525);
FORCEPROP 1 LASTPIN (2325 1600) $PN 2
J 0
(2330 1610);
DISPLAY 0.617021 (2330 1610);
PAINT ORANGE (2330 1610);
FORCEPROP 1 LASTPIN (2325 1800) $PN 1
J 0
(2330 1762);
DISPLAY 0.617021 (2330 1762);
PAINT ORANGE (2330 1762);
FORCEPROP 1 LAST TOLERANCE 1%
J 0
(2370 1725);
DISPLAY 0.617021 (2370 1725);
PAINT SKYBLUE (2370 1725);
FORCEPROP 1 LAST MATERIAL CHIP
J 0
(2365 1625);
DISPLAY 0.617021 (2365 1625);
PAINT SKYBLUE (2365 1625);
FORCEPROP 1 LAST WATTAGE 1/16W
J 0
(2365 1675);
DISPLAY 0.617021 (2365 1675);
PAINT SKYBLUE (2365 1675);
FORCEPROP 1 LAST VALUE 49.9K
J 0
(2370 1775);
DISPLAY 0.617021 (2370 1775);
PAINT SKYBLUE (2370 1775);
FORCEPROP 1 LAST LOCATION R2L19
J 0
(2370 1825);
DISPLAY 0.617021 (2370 1825);
PAINT AQUA (2370 1825);
FORCEPROP 1 LAST PART_NUMBER G21796-048
J 0
(2365 1575);
DISPLAY 0.617021 (2365 1575);
PAINT BLUE (2365 1575);
FORCEPROP 2 LAST CDS_LIB mstr_discrete
J 0
(2325 1700);
PAINT ORANGE (2325 1700);
DISPLAY INVISIBLE (2325 1700);
FORCEPROP 1 LAST PATH I80
J 0
(2375 1875);
DISPLAY 0.978723 (2375 1875);
PAINT WHITE (2375 1875);
DISPLAY INVISIBLE (2375 1875);
FORCEPROP 2 LAST CDS_LOCATION R2L19
J 0
(2370 1825);
DISPLAY 0.617021 (2370 1825);
PAINT AQUA (2370 1825);
DISPLAY INVISIBLE (2370 1825);
FORCEPROP 2 LAST SEC 1
J 0
(2375 1925);
DISPLAY 0.680851 (2375 1925);
PAINT MONO (2375 1925);
DISPLAY INVISIBLE (2375 1925);
FORCEPROP 2 LAST SEC_TYPE 0402
J 0
(2375 1925);
DISPLAY 1.021277 (2375 1925);
PAINT ORANGE (2375 1925);
DISPLAY INVISIBLE (2375 1925);
FORCEPROP 2 LAST ROOM P1V8_PCH_STBY_VR
J 0
(2375 1875);
PAINT MONO (2375 1875);
DISPLAY INVISIBLE (2375 1875);
FORCEADD RES..2
(2325 2275);
FORCEPROP 1 LASTPIN (2325 2175) $PN 2
J 0
(2330 2185);
DISPLAY 0.617021 (2330 2185);
PAINT ORANGE (2330 2185);
FORCEPROP 1 LAST MATERIAL CHIP
J 0
(2365 2200);
DISPLAY 0.617021 (2365 2200);
PAINT SKYBLUE (2365 2200);
FORCEPROP 1 LAST PACK_TYPE 0402
J 0
(2365 2100);
DISPLAY 0.617021 (2365 2100);
PAINT SKYBLUE (2365 2100);
FORCEPROP 1 LAST WATTAGE 1/16W
J 0
(2365 2250);
DISPLAY 0.617021 (2365 2250);
PAINT SKYBLUE (2365 2250);
FORCEPROP 1 LAST TOLERANCE 1.0%
J 0
(2370 2300);
DISPLAY 0.617021 (2370 2300);
PAINT SKYBLUE (2370 2300);
FORCEPROP 1 LASTPIN (2325 2375) $PN 1
J 0
(2330 2337);
DISPLAY 0.617021 (2330 2337);
PAINT ORANGE (2330 2337);
FORCEPROP 1 LAST LOCATION R2L20
J 0
(2370 2400);
DISPLAY 0.617021 (2370 2400);
PAINT AQUA (2370 2400);
FORCEPROP 1 LAST VALUE 63.4K
J 0
(2370 2350);
DISPLAY 0.617021 (2370 2350);
PAINT SKYBLUE (2370 2350);
FORCEPROP 1 LAST PART_NUMBER G21796-327
J 0
(2365 2150);
DISPLAY 0.617021 (2365 2150);
PAINT BLUE (2365 2150);
FORCEPROP 2 LAST CDS_LIB mstr_discrete
J 0
(2325 2275);
PAINT ORANGE (2325 2275);
DISPLAY INVISIBLE (2325 2275);
FORCEPROP 2 LAST SEC_TYPE 0402
J 0
(2375 2500);
DISPLAY 1.021277 (2375 2500);
PAINT ORANGE (2375 2500);
DISPLAY INVISIBLE (2375 2500);
FORCEPROP 2 LAST ROOM P1V8_PCH_STBY_VR
J 0
(2375 2450);
PAINT MONO (2375 2450);
DISPLAY INVISIBLE (2375 2450);
FORCEPROP 2 LAST SEC 1
J 0
(2375 2500);
DISPLAY 0.680851 (2375 2500);
PAINT MONO (2375 2500);
DISPLAY INVISIBLE (2375 2500);
FORCEPROP 2 LAST CDS_LOCATION R2L20
J 0
(2370 2400);
DISPLAY 0.617021 (2370 2400);
PAINT AQUA (2370 2400);
DISPLAY INVISIBLE (2370 2400);
FORCEPROP 1 LAST PATH I81
J 0
(2375 2450);
DISPLAY 0.978723 (2375 2450);
PAINT WHITE (2375 2450);
DISPLAY INVISIBLE (2375 2450);
FORCEADD P3V3_STBY..1
(-1750 3650);
FORCEPROP 3 LASTPIN (-1750 3600) SIG_NAME P3V3_STBY\g
J 0
(-1740 3610);
DISPLAY 0.659574 (-1740 3610);
PAINT MONO (-1740 3610);
DISPLAY INVISIBLE (-1740 3610);
FORCEPROP 1 LAST HDL_POWER P3V3_STBY
J 0
(-2050 3525);
DISPLAY 0.872340 (-2050 3525);
PAINT ORANGE (-2050 3525);
DISPLAY INVISIBLE (-2050 3525);
FORCEPROP 1 LAST PATH I85
J 0
(-1705 3652);
DISPLAY 0.340426 (-1705 3652);
PAINT GREEN (-1705 3652);
DISPLAY INVISIBLE (-1705 3652);
FORCEPROP 1 LAST BODY_TYPE PLUMBING
J 0
(-1795 3607);
DISPLAY 0.340426 (-1795 3607);
PAINT GREEN (-1795 3607);
DISPLAY INVISIBLE (-1795 3607);
FORCEPROP 1 LAST SIZE 1B
J 0
(-1705 3672);
DISPLAY 0.340426 (-1705 3672);
PAINT GREEN (-1705 3672);
DISPLAY INVISIBLE (-1705 3672);
FORCEPROP 2 LAST CDS_LIB mstr_symbols
J 0
(-1750 3650);
PAINT MONO (-1750 3650);
DISPLAY INVISIBLE (-1750 3650);
FORCEPROP 1 LAST VOLTAGE 3.3V
J 0
(-1795 3607);
DISPLAY 0.340426 (-1795 3607);
PAINT SKYBLUE (-1795 3607);
DISPLAY INVISIBLE (-1795 3607);
FORCEADD RT9059..1
(-50 2725);
FORCEPROP 2 LASTPIN (-550 2525) $PN 6
J 2
(-560 2535);
DISPLAY 0.617021 (-560 2535);
PAINT ORANGE (-560 2535);
FORCEPROP 2 LASTPIN (-550 2675) $PN 7
J 2
(-560 2685);
DISPLAY 0.617021 (-560 2685);
PAINT ORANGE (-560 2685);
FORCEPROP 2 LASTPIN (-550 2725) $PN 8
J 2
(-560 2735);
DISPLAY 0.617021 (-560 2735);
PAINT ORANGE (-560 2735);
FORCEPROP 2 LASTPIN (-550 2775) $PN 9
J 2
(-560 2785);
DISPLAY 0.617021 (-560 2785);
PAINT ORANGE (-560 2785);
FORCEPROP 2 LASTPIN (-550 2925) $PN 10
J 2
(-560 2935);
DISPLAY 0.617021 (-560 2935);
PAINT ORANGE (-560 2935);
FORCEPROP 1 LAST PART_NUMBER H65765-001
J 0
(-500 2325);
DISPLAY 0.617021 (-500 2325);
PAINT BLUE (-500 2325);
FORCEPROP 1 LAST MATERIAL IC
J 0
(-500 3125);
DISPLAY 0.617021 (-500 3125);
PAINT SKYBLUE (-500 3125);
FORCEPROP 1 LAST LOCATION EU8A2
J 0
(-500 3175);
DISPLAY 0.617021 (-500 3175);
PAINT AQUA (-500 3175);
FORCEPROP 2 LASTPIN (450 2525) $PN 4
J 0
(460 2535);
DISPLAY 0.617021 (460 2535);
PAINT ORANGE (460 2535);
FORCEPROP 2 LASTPIN (450 2775) $PN 3
J 0
(460 2785);
DISPLAY 0.617021 (460 2785);
PAINT ORANGE (460 2785);
FORCEPROP 2 LASTPIN (450 2725) $PN 2
J 0
(460 2735);
DISPLAY 0.617021 (460 2735);
PAINT ORANGE (460 2735);
FORCEPROP 2 LASTPIN (450 2675) $PN 1
J 0
(460 2685);
DISPLAY 0.617021 (460 2685);
PAINT ORANGE (460 2685);
FORCEPROP 2 LASTPIN (450 2925) $PN 5
J 0
(460 2935);
DISPLAY 0.617021 (460 2935);
PAINT ORANGE (460 2935);
FORCEPROP 2 LASTPIN (450 2425) $PN 11
J 0
(460 2435);
DISPLAY 0.617021 (460 2435);
PAINT ORANGE (460 2435);
FORCEPROP 2 LAST CDS_LIB mstr_vreg
J 0
(-50 2725);
PAINT MONO (-50 2725);
DISPLAY INVISIBLE (-50 2725);
FORCEPROP 0 LAST ROOM P1V8_PCH_STBY_VR
J 0
(-500 3275);
DISPLAY 1.021277 (-500 3275);
PAINT ORANGE (-500 3275);
DISPLAY INVISIBLE (-500 3275);
FORCEPROP 2 LAST CDS_LOCATION EU8A2
J 0
(-500 3175);
DISPLAY 0.617021 (-500 3175);
PAINT AQUA (-500 3175);
DISPLAY INVISIBLE (-500 3175);
FORCEPROP 2 LAST SEC 1
J 0
(-500 3225);
DISPLAY 0.680851 (-500 3225);
PAINT MONO (-500 3225);
DISPLAY INVISIBLE (-500 3225);
FORCEPROP 2 LAST SEC_TYPE DFN
J 0
(-500 3225);
DISPLAY 1.021277 (-500 3225);
PAINT ORANGE (-500 3225);
DISPLAY INVISIBLE (-500 3225);
FORCEPROP 1 LAST PACK_TYPE DFN
J 0
(-500 3225);
PAINT SKYBLUE (-500 3225);
DISPLAY INVISIBLE (-500 3225);
FORCEPROP 1 LAST PATH I86
J 0
(0 3125);
PAINT GREEN (0 3125);
DISPLAY INVISIBLE (0 3125);
FORCEADD RES..1
(2175 3650);
FORCEPROP 1 LAST WATTAGE 1/16W
J 2
(2150 3500);
DISPLAY 0.617021 (2150 3500);
PAINT SKYBLUE (2150 3500);
FORCEPROP 1 LAST VALUE 22.1
J 2
(2150 3550);
DISPLAY 0.617021 (2150 3550);
PAINT SKYBLUE (2150 3550);
FORCEPROP 1 LAST MATERIAL CHIP
J 0
(2175 3500);
DISPLAY 0.617021 (2175 3500);
PAINT SKYBLUE (2175 3500);
FORCEPROP 1 LAST PACK_TYPE 0402
J 0
(2425 3500);
DISPLAY 0.617021 (2425 3500);
PAINT SKYBLUE (2425 3500);
FORCEPROP 1 LAST TOLERANCE 1.0%
J 0
(2175 3550);
DISPLAY 0.617021 (2175 3550);
PAINT SKYBLUE (2175 3550);
FORCEPROP 1 LASTPIN (2075 3650) $PN 1
J 0
(2087 3662);
DISPLAY 0.617021 (2087 3662);
PAINT ORANGE (2087 3662);
FORCEPROP 1 LAST LOCATION R8A11
J 0
(2125 3700);
DISPLAY 0.617021 (2125 3700);
PAINT AQUA (2125 3700);
FORCEPROP 1 LASTPIN (2275 3650) $PN 2
J 0
(2237 3662);
DISPLAY 0.617021 (2237 3662);
PAINT ORANGE (2237 3662);
FORCEPROP 1 LAST PART_NUMBER G21796-250
J 0
(2125 3750);
DISPLAY 0.617021 (2125 3750);
PAINT BLUE (2125 3750);
FORCEPROP 2 LAST CDS_LOCATION R8A11
J 0
(2125 3700);
DISPLAY 0.617021 (2125 3700);
PAINT AQUA (2125 3700);
DISPLAY INVISIBLE (2125 3700);
FORCEPROP 2 LAST CDS_LIB mstr_discrete
J 0
(2175 3650);
PAINT MONO (2175 3650);
DISPLAY INVISIBLE (2175 3650);
FORCEPROP 1 LAST PATH I90
J 0
(2125 3800);
DISPLAY 0.978723 (2125 3800);
PAINT WHITE (2125 3800);
DISPLAY INVISIBLE (2125 3800);
FORCEPROP 2 LAST SEC_TYPE 0402
J 0
(2125 3850);
DISPLAY 1.021277 (2125 3850);
PAINT ORANGE (2125 3850);
DISPLAY INVISIBLE (2125 3850);
FORCEPROP 2 LAST SEC 1
J 0
(2125 3850);
DISPLAY 0.680851 (2125 3850);
PAINT MONO (2125 3850);
DISPLAY INVISIBLE (2125 3850);
FORCEPROP 0 LAST ROOM P1V8_PCH_STBY_VR
J 0
(2125 3850);
DISPLAY 1.021277 (2125 3850);
PAINT ORANGE (2125 3850);
DISPLAY INVISIBLE (2125 3850);
FORCEADD GND..1
(2325 1425);
FORCEPROP 3 LASTPIN (2325 1475) SIG_NAME GND\g
J 0
(2335 1485);
DISPLAY 0.659574 (2335 1485);
PAINT MONO (2335 1485);
DISPLAY INVISIBLE (2335 1485);
FORCEPROP 2 LAST BOM_COST P1V8_PCH_STBY_VR
J 0
(1925 1500);
DISPLAY 1.659574 (1925 1500);
PAINT MONO (1925 1500);
DISPLAY INVISIBLE (1925 1500);
FORCEPROP 2 LAST ROOM P1V8_PCH_STBY_VR
J 0
(1675 1500);
DISPLAY 1.659574 (1675 1500);
PAINT ORANGE (1675 1500);
DISPLAY INVISIBLE (1675 1500);
FORCEPROP 1 LAST PATH I91
J 0
(2400 1425);
DISPLAY 0.872340 (2400 1425);
PAINT AQUA (2400 1425);
DISPLAY INVISIBLE (2400 1425);
FORCEPROP 1 LAST BODY_TYPE PLUMBING
J 0
(2280 1382);
DISPLAY 0.340426 (2280 1382);
PAINT GREEN (2280 1382);
DISPLAY INVISIBLE (2280 1382);
FORCEPROP 2 LAST CDS_LIB mstr_symbols
J 0
(2325 1425);
PAINT MONO (2325 1425);
DISPLAY INVISIBLE (2325 1425);
FORCEPROP 1 LAST SIZE 1B
J 0
(2400 1375);
DISPLAY 1.489362 (2400 1375);
PAINT GREEN (2400 1375);
DISPLAY INVISIBLE (2400 1375);
FORCEPROP 1 LAST VOLTAGE 0.0V
J 0
(2280 1382);
DISPLAY 0.340426 (2280 1382);
PAINT SKYBLUE (2280 1382);
DISPLAY INVISIBLE (2280 1382);
FORCEPROP 1 LAST HDL_POWER GND
J 0
(2325 1575);
DISPLAY 1.489362 (2325 1575);
PAINT GREEN (2325 1575);
DISPLAY INVISIBLE (2325 1575);
FORCEADD GND..1
(-1500 1950);
FORCEPROP 3 LASTPIN (-1500 2000) SIG_NAME GND\g
J 0
(-1490 2010);
DISPLAY 0.659574 (-1490 2010);
PAINT MONO (-1490 2010);
DISPLAY INVISIBLE (-1490 2010);
FORCEPROP 2 LAST ROOM P1V8_PCH_STBY_VR
J 0
(-2150 2025);
DISPLAY 1.659574 (-2150 2025);
PAINT ORANGE (-2150 2025);
DISPLAY INVISIBLE (-2150 2025);
FORCEPROP 1 LAST PATH I92
J 0
(-1425 1950);
DISPLAY 0.872340 (-1425 1950);
PAINT AQUA (-1425 1950);
DISPLAY INVISIBLE (-1425 1950);
FORCEPROP 1 LAST BODY_TYPE PLUMBING
J 0
(-1545 1907);
DISPLAY 0.340426 (-1545 1907);
PAINT GREEN (-1545 1907);
DISPLAY INVISIBLE (-1545 1907);
FORCEPROP 2 LAST CDS_LIB mstr_symbols
J 0
(-1500 1950);
PAINT MONO (-1500 1950);
DISPLAY INVISIBLE (-1500 1950);
FORCEPROP 1 LAST SIZE 1B
J 0
(-1425 1900);
DISPLAY 1.489362 (-1425 1900);
PAINT GREEN (-1425 1900);
DISPLAY INVISIBLE (-1425 1900);
FORCEPROP 1 LAST VOLTAGE 0.0V
J 0
(-1545 1907);
DISPLAY 0.340426 (-1545 1907);
PAINT SKYBLUE (-1545 1907);
DISPLAY INVISIBLE (-1545 1907);
FORCEPROP 2 LAST BOM_COST P1V8_PCH_STBY_VR
J 0
(-1900 2025);
DISPLAY 1.659574 (-1900 2025);
PAINT MONO (-1900 2025);
DISPLAY INVISIBLE (-1900 2025);
FORCEPROP 1 LAST HDL_POWER GND
J 0
(-1500 2100);
DISPLAY 1.489362 (-1500 2100);
PAINT GREEN (-1500 2100);
DISPLAY INVISIBLE (-1500 2100);
FORCEADD DESIGN_NOTE..1
(-450 1500);
FORCEPROP 2 LAST BOM_COST SB
J 0
(-650 1450);
DISPLAY 1.361702 (-650 1450);
PAINT ORANGE (-650 1450);
DISPLAY INVISIBLE (-650 1450);
FORCEPROP 1 LAST COMMENT_BODY TRUE
J 0
(-425 1600);
DISPLAY 1.319149 (-425 1600);
PAINT ORANGE (-425 1600);
DISPLAY INVISIBLE (-425 1600);
FORCEPROP 2 LAST CDS_LIB mstr_symbols
J 0
(-450 1500);
PAINT ORANGE (-450 1500);
DISPLAY INVISIBLE (-450 1500);
FORCEADD DNS..2
(-1495 2195);
PAINT RED (-1495 2195);
FORCEPROP 1 LAST COMMENT_BODY TRUE
R 1
J 0
(-1420 1970);
DISPLAY 0.872340 (-1420 1970);
PAINT GREEN (-1420 1970);
DISPLAY INVISIBLE (-1420 1970);
FORCEPROP 2 LAST CDS_LIB mstr_misc
J 0
(-1495 2195);
PAINT ORANGE (-1495 2195);
DISPLAY INVISIBLE (-1495 2195);
FORCEADD DESIGN_NOTE..1
(2700 4950);
PAINT SKYBLUE (2700 4950);
FORCEPROP 0 LAST L7 DC TOLERANCE = +- 1.5 %
J 0
(2550 4500);
DISPLAY 1.170213 (2550 4500);
PAINT WHITE (2550 4500);
FORCEPROP 0 LAST L6 AC TOLERANCE = +- 3.0 %
J 0
(2550 4425);
DISPLAY 1.170213 (2550 4425);
PAINT WHITE (2550 4425);
FORCEPROP 0 LAST L5 STEP RATE = TBDA/US
J 0
(2550 4350);
DISPLAY 1.170213 (2550 4350);
PAINT WHITE (2550 4350);
FORCEPROP 0 LAST L2 VOUT = 1.8 V
J 0
(2550 4725);
DISPLAY 1.170213 (2550 4725);
PAINT WHITE (2550 4725);
FORCEPROP 0 LAST L3 TDC = 0.6 A
J 0
(2550 4650);
DISPLAY 1.170213 (2550 4650);
PAINT WHITE (2550 4650);
FORCEPROP 0 LAST L4 IMAX =1.0 A
J 0
(2550 4575);
DISPLAY 1.170213 (2550 4575);
PAINT WHITE (2550 4575);
FORCEPROP 0 LAST L1 P1V8_PCH_STBY VR SPECIFICATION
J 0
(2500 4800);
DISPLAY 1.170213 (2500 4800);
PAINT WHITE (2500 4800);
FORCEPROP 2 LAST ROOM P1V8_PCH_STBY_VR
J 0
(2100 4825);
DISPLAY 1.042553 (2100 4825);
PAINT ORANGE (2100 4825);
DISPLAY INVISIBLE (2100 4825);
FORCEPROP 2 LAST BOM_COST P1V8_PCH_STBY_VR
J 0
(2100 4875);
DISPLAY 1.042553 (2100 4875);
PAINT ORANGE (2100 4875);
DISPLAY INVISIBLE (2100 4875);
FORCEPROP 2 LAST CDS_LIB mstr_symbols
J 0
(2700 4950);
PAINT MONO (2700 4950);
DISPLAY INVISIBLE (2700 4950);
FORCEPROP 1 LAST COMMENT_BODY TRUE
J 0
(2725 5050);
DISPLAY 0.957447 (2725 5050);
PAINT PEACH (2725 5050);
DISPLAY INVISIBLE (2725 5050);
FORCEADD INTEL_CORP_BPAGE..1
(4250 200);
FORCEPROP 1 LAST CDS_CON_LAST_MODIFIED Tue Dec 01 11:52:30 2015
J 0
(2825 525);
PAINT ORANGE (2825 525);
DISPLAY INVISIBLE (2825 525);
FORCEPROP 1 LAST CUSTOM_TXT_CDS <CURRENT_DESIGN_SHEET> OF <TOTAL_DESIGN_SHEETS>
J 0
(3750 225);
PAINT GREEN (3750 225);
FORCEPROP 1 LAST CUSTOM_TXT_CDS <CON_LAST_MODIFIED>
J 0
(2325 550);
PAINT GREEN (2325 550);
FORCEPROP 2 LAST CUSTOM_TXT_CDS <XR_PAGE_TITLE>
J 0
(-3640 5450);
DISPLAY 0.638298 (-3640 5450);
PAINT PINK (-3640 5450);
DISPLAY INVISIBLE (-3640 5450);
FORCEPROP 1 LAST SCH_TITLE P1V8 PCH STBY VR
J 0
(-3700 250);
DISPLAY 1.212766 (-3700 250);
PAINT ORANGE (-3700 250);
FORCEPROP 1 LAST SCH_ADDRESS2 P.O. BOX 58119
J 0
(275 275);
DISPLAY 0.617021 (275 275);
PAINT GREEN (275 275);
FORCEPROP 1 LAST SCH_ADDRESS1 2200 Mission College Blvd.
J 0
(275 325);
DISPLAY 0.617021 (275 325);
PAINT GREEN (275 325);
FORCEPROP 1 LAST SCH_ADDRESS3 Santa Clara, CA 95052-8119
J 0
(275 225);
DISPLAY 0.617021 (275 225);
PAINT GREEN (275 225);
FORCEPROP 1 LAST SCH_NUMBER H4694802
J 0
(2950 350);
DISPLAY 1.212766 (2950 350);
PAINT YELLOW (2950 350);
FORCEPROP 1 LAST SCH_DEPT BESD
J 1
(-200 300);
DISPLAY 1.212766 (-200 300);
PAINT YELLOW (-200 300);
FORCEPROP 1 LAST SCH_REV 2.420
J 0
(4000 350);
DISPLAY 0.978723 (4000 350);
PAINT YELLOW (4000 350);
FORCEPROP 2 LAST PAGE_BORDER TRUE
J 0
(-3640 5450);
DISPLAY 0.638298 (-3640 5450);
PAINT PINK (-3640 5450);
DISPLAY INVISIBLE (-3640 5450);
FORCEPROP 1 LAST COMMENT_BODY TRUE
J 0
(4262 212);
DISPLAY 0.468085 (4262 212);
PAINT GREEN (4262 212);
DISPLAY INVISIBLE (4262 212);
FORCEPROP 2 LAST CDS_LIB mstr_symbols
J 0
(4250 200);
PAINT MONO (4250 200);
DISPLAY INVISIBLE (4250 200);
FORCEPROP 2 LAST CDS_XR_PAGE_TITLE CR-237 : @BASEBOARD_FAB2_LIB.BASEBOARD_FAB2(SCH_1):PAGE237
J 0
(-3640 5450);
DISPLAY 0.638298 (-3640 5450);
PAINT PINK (-3640 5450);
DISPLAY INVISIBLE (-3640 5450);
WIRE 16 -1 (2800 2025)(2800 1575);
WIRE 16 -1 (2800 1575)(3100 1575);
WIRE 16 -1 (3100 2100)(3100 1575);
WIRE 16 -1 (3375 1575)(3100 1575);
WIRE 16 -1 (3375 2050)(3375 1575);
WIRE 16 -1 (3375 1575)(3500 1575);
WIRE 16 -1 (3500 1575)(3650 1575);
WIRE 16 -1 (3500 1450)(3500 1575);
WIRE 16 -1 (3900 1575)(3650 1575);
WIRE 16 -1 (3650 2100)(3650 1575);
WIRE 16 -1 (3900 1750)(3900 1575);
WIRE 16 -1 (-1975 2850)(-1975 3050);
WIRE 16 -1 (-1550 2825)(-1550 3075);
WIRE 16 -1 (450 2775)(550 2775);
WIRE 16 -1 (550 2775)(550 2725);
WIRE 16 -1 (450 2725)(550 2725);
WIRE 16 -1 (550 2725)(550 2675);
WIRE 16 -1 (2325 2675)(550 2675);
WIRE 16 -1 (550 2675)(450 2675);
WIRE 16 -1 (2800 2675)(2325 2675);
WIRE 16 -1 (2325 2675)(2325 2375);
WIRE 16 -1 (2800 2225)(2800 2675);
WIRE 16 -1 (3100 2675)(2800 2675);
WIRE 16 -1 (3100 2300)(3100 2675);
WIRE 16 -1 (3375 2675)(3100 2675);
WIRE 16 -1 (3375 2250)(3375 2675);
WIRE 16 -1 (3650 2675)(3375 2675);
WIRE 16 -1 (3650 2300)(3650 2675);
WIRE 16 -1 (3900 2675)(3650 2675);
WIRE 16 -1 (3900 1950)(3900 2675);
WIRE 16 -1 (3900 2675)(3925 2675);
WIRE 16 -1 (3925 2675)(3925 2800);
WIRE 16 -1 (1350 3200)(1350 3375);
WIRE 16 -1 (1350 4075)(1350 3975);
WIRE 16 -1 (525 2350)(525 2425);
FORCEPROP 0 LAST VOLTAGE 0 V
J 0
(540 2421);
DISPLAY 1.617021 (540 2421);
PAINT SKYBLUE (540 2421);
DISPLAY INVISIBLE (540 2421);
WIRE 16 -1 (525 2425)(450 2425);
WIRE 16 -1 (-550 2675)(-700 2675);
WIRE 16 -1 (-700 2675)(-700 2725);
WIRE 16 -1 (-550 2725)(-700 2725);
WIRE 16 -1 (-700 2725)(-700 2775);
WIRE 16 -1 (-700 2775)(-550 2775);
WIRE 16 -1 (-700 2775)(-1075 2775);
WIRE 16 -1 (-1075 2775)(-1075 2925);
WIRE 16 -1 (-1075 2925)(-550 2925);
WIRE 16 -1 (-1075 2925)(-1075 3400);
WIRE 16 -1 (-1075 3400)(-1550 3400);
WIRE 16 -1 (-1550 3275)(-1550 3400);
WIRE 16 -1 (-1550 3400)(-1750 3400);
WIRE 16 -1 (-1975 3400)(-1750 3400);
WIRE 16 -1 (-1750 3600)(-1750 3400);
WIRE 16 -1 (-1975 3400)(-1975 3250);
WIRE 16 -1 (2325 1600)(2325 1475);
WIRE 16 -1 (-1500 2000)(-1500 2100);
FORCEPROP 0 LAST VOLTAGE 0V
J 0
(-1500 2125);
DISPLAY 1.021277 (-1500 2125);
PAINT SKYBLUE (-1500 2125);
DISPLAY INVISIBLE (-1500 2125);
WIRE 16 -1 (2925 3650)(2275 3650);
FORCEPROP 2 LAST SIG_NAME PWRGD_P1V8_PCH_STBY
J 0
(2362 3665);
DISPLAY 0.617021 (2362 3665);
PAINT ORANGE (2362 3665);
WIRE 16 -1 (2325 1800)(2325 1875);
WIRE 16 -1 (2325 2175)(2325 1875);
WIRE 16 -1 (2325 1875)(850 1875);
FORCEPROP 2 LAST SIG_NAME VR_P1V8_PCH_STBY_FB
J 0
(1227 1895);
DISPLAY 0.617021 (1227 1895);
PAINT ORANGE (1227 1895);
FORCEPROP 2 LASTPROP $XRERR UNIQUE?
J 0
(987 1895);
DISPLAY 0.638298 (987 1895);
PAINT MONO (987 1895);
DISPLAY INVISIBLE (987 1895);
WIRE 16 -1 (850 1875)(850 2525);
WIRE 16 -1 (850 2525)(450 2525);
WIRE 16 -1 (2075 3650)(1725 3650);
FORCEPROP 2 LAST SIG_NAME PWRGD_P1V8_PCH_STBY_R
J 0
(1512 3665);
DISPLAY 0.617021 (1512 3665);
PAINT ORANGE (1512 3665);
FORCEPROP 2 LASTPROP $XRERR UNIQUE?
J 0
(1272 3665);
DISPLAY 0.638298 (1272 3665);
PAINT MONO (1272 3665);
DISPLAY INVISIBLE (1272 3665);
WIRE 16 -1 (1725 3650)(1350 3650);
WIRE 16 -1 (1725 3650)(1725 2925);
WIRE 16 -1 (1725 2925)(450 2925);
WIRE 16 -1 (1350 3775)(1350 3650);
WIRE 16 -1 (1350 3575)(1350 3650);
WIRE 16 -1 (1925 1250)(1925 1350);
WIRE 16 -1 (1925 1150)(1925 1250);
WIRE 16 -1 (-675 1250)(1925 1250);
WIRE 16 -1 (1925 1350)(1150 1350);
WIRE 16 -1 (1150 1350)(1150 1050);
WIRE 16 -1 (1150 1350)(800 1350);
WIRE 16 -1 (-675 1350)(-675 1250);
WIRE 16 -1 (-675 1250)(-675 1150);
WIRE 16 -1 (1925 1050)(1925 1150);
WIRE 16 -1 (-675 1150)(1925 1150);
WIRE 16 -1 (-675 1150)(-675 1050);
WIRE 16 -1 (1925 1050)(1150 1050);
WIRE 16 -1 (450 1350)(-675 1350);
WIRE 16 -1 (800 1350)(800 1050);
WIRE 16 -1 (800 1350)(450 1350);
WIRE 16 -1 (1150 1050)(800 1050);
WIRE 16 -1 (800 1050)(450 1050);
WIRE 16 -1 (450 1350)(450 1050);
WIRE 16 -1 (450 1050)(-675 1050);
WIRE 16 -1 (-1500 2525)(-550 2525);
WIRE 16 -1 (-1500 2300)(-1500 2525);
WIRE 16 -1 (-1500 2525)(-2700 2525);
DOT 1 (-675 1150);
DOT 1 (-675 1250);
DOT 1 (-1500 2525);
DOT 1 (-1075 2925);
DOT 1 (-1550 3400);
DOT 1 (-1750 3400);
DOT 1 (-700 2725);
DOT 1 (-700 2775);
DOT 1 (450 1050);
DOT 1 (450 1350);
DOT 1 (800 1050);
DOT 1 (800 1350);
DOT 1 (1150 1350);
DOT 1 (1150 1050);
DOT 1 (1925 1150);
DOT 1 (1925 1250);
DOT 1 (550 2675);
DOT 1 (550 2725);
DOT 1 (1350 3650);
DOT 1 (1725 3650);
DOT 1 (2325 1875);
DOT 1 (3100 1575);
DOT 1 (3500 1575);
DOT 1 (3375 1575);
DOT 1 (3650 1575);
DOT 1 (2325 2675);
DOT 1 (2800 2675);
DOT 1 (3100 2675);
DOT 1 (3375 2675);
DOT 1 (3650 2675);
DOT 1 (3900 2675);
FORCENOTE
ROOM=P1V8_PCH_STBY_VR
(-3700 450) 0;
DISPLAY LEFT (-3700 450);
DISPLAY 1.276596 (-3700 450);
PAINT PURPLE (-3700 450);
FORCENOTE
BOM COST=P1V8_PCH_STBY_VR
(-3700 375) 0;
DISPLAY LEFT (-3700 375);
DISPLAY 1.276596 (-3700 375);
PAINT PURPLE (-3700 375);
FORCENOTE
PCH
(-250 1275) 0;
DISPLAY LEFT (-250 1275);
DISPLAY 1.276596 (-250 1275);
PAINT PURPLE (-250 1275);
FORCENOTE
WELLSBURG (INTERPOSER)
(-650 1075) 0;
DISPLAY LEFT (-650 1075);
DISPLAY 1.276596 (-650 1075);
PAINT PURPLE (-650 1075);
FORCENOTE
LEWISBURG
(-400 1175) 0;
DISPLAY LEFT (-400 1175);
DISPLAY 1.276596 (-400 1175);
PAINT PURPLE (-400 1175);
FORCENOTE
R1
(600 1275) 0;
DISPLAY LEFT (600 1275);
DISPLAY 1.276596 (600 1275);
PAINT PURPLE (600 1275);
FORCENOTE
43.2K
(525 1075) 0;
DISPLAY LEFT (525 1075);
DISPLAY 1.276596 (525 1075);
PAINT PURPLE (525 1075);
FORCENOTE
63.4K
(525 1175) 0;
DISPLAY LEFT (525 1175);
DISPLAY 1.276596 (525 1175);
PAINT PURPLE (525 1175);
FORCENOTE
49.9K
(825 1175) 0;
DISPLAY LEFT (825 1175);
DISPLAY 1.276596 (825 1175);
PAINT PURPLE (825 1175);
FORCENOTE
49.9K
(825 1075) 0;
DISPLAY LEFT (825 1075);
DISPLAY 1.276596 (825 1075);
PAINT PURPLE (825 1075);
FORCENOTE
R2
(925 1275) 0;
DISPLAY LEFT (925 1275);
DISPLAY 1.276596 (925 1275);
PAINT PURPLE (925 1275);
FORCENOTE
VOLTAGE SETTING
(200 1425) 0;
DISPLAY LEFT (200 1425);
DISPLAY 1.276596 (200 1425);
PAINT PURPLE (200 1425);
FORCENOTE
VOLTAGE
(1325 1275) 0;
DISPLAY LEFT (1325 1275);
DISPLAY 0.617021 (1325 1275);
PAINT PURPLE (1325 1275);
FORCENOTE
1.5V
(1425 1075) 0;
DISPLAY LEFT (1425 1075);
DISPLAY 1.276596 (1425 1075);
PAINT PURPLE (1425 1075);
FORCENOTE
1.8V
(1425 1175) 0;
DISPLAY LEFT (1425 1175);
DISPLAY 1.276596 (1425 1175);
PAINT PURPLE (1425 1175);
FORCENOTE
R2
(2125 1675) 0;
DISPLAY LEFT (2125 1675);
DISPLAY 1.276596 (2125 1675);
PAINT PURPLE (2125 1675);
FORCENOTE
R1
(2125 2250) 0;
DISPLAY LEFT (2125 2250);
DISPLAY 1.276596 (2125 2250);
PAINT PURPLE (2125 2250);
QUIT
